(kicad_pcb
	(version 20260206)
	(generator "pcbnew")
	(generator_version "10.0")
	(general
		(thickness 1.6)
		(legacy_teardrops no)
	)
	(paper "A4")
	(title_block
		(title "v1-chassis-manager — T6M_CM_d_v01_1031_1645.brd")
		(comment 1 "Open CloudServer (Microsoft) / footprints 140-149 of 2512")
	)
	(layers
		(0 "F.Cu" signal "TOP")
		(4 "In1.Cu" signal "GND1")
		(6 "In2.Cu" signal "IN1")
		(8 "In3.Cu" signal "VCC1")
		(10 "In4.Cu" signal "VCC2")
		(12 "In5.Cu" signal "GND2")
		(14 "In6.Cu" signal "IN2")
		(16 "In7.Cu" signal "IN3")
		(18 "In8.Cu" signal "GND3")
		(2 "B.Cu" signal "BOTTOM")
		(9 "F.Adhes" user "F.Adhesive")
		(11 "B.Adhes" user "B.Adhesive")
		(13 "F.Paste" user "Package Geometry/Pastemask Top")
		(15 "B.Paste" user "Package Geometry/Pastemask Bottom")
		(5 "F.SilkS" user "Ref Des/Silkscreen Top")
		(7 "B.SilkS" user "Ref Des/Silkscreen Bottom")
		(1 "F.Mask" user "Board Geometry/Soldermask Top")
		(3 "B.Mask" user "Board Geometry/Soldermask Bottom")
		(17 "Dwgs.User" user "User.Drawings")
		(19 "Cmts.User" user "User.Comments")
		(21 "Eco1.User" user "User.Eco1")
		(23 "Eco2.User" user "User.Eco2")
		(25 "Edge.Cuts" user "Board Geometry/Outline")
		(27 "Margin" user)
		(31 "F.CrtYd" user "Package Geometry/Place Bound Top")
		(29 "B.CrtYd" user "Package Geometry/Place Bound Bottom")
		(35 "F.Fab" user "Ref Des/Assembly Top")
		(33 "B.Fab" user "Ref Des/Assembly Bottom")
	)
	(footprint ""
		(layer "F.Cu")
		(at 40.668194 -15.20698)
		(property "Reference" "PJ9"
			(at 0.179578 -0.49022 90)
			(unlocked yes)
			(layer "F.SilkS")
			(effects
				(font
					(size 0.7874 0.5842)
					(thickness 0.1524)
				)
				(justify left)
			)
		)
		(property "Value" ""
			(at 0 0 0)
			(layer "F.Fab")
			(effects
				(font
					(size 1.27 1.27)
				)
			)
		)
		(duplicate_pad_numbers_are_jumpers no)
		(fp_poly
			(pts
				(xy 0.2794 0.907796) (xy 0.254 0.907796) (xy 0.254 1.0414) (xy -0.254 1.0414) (xy -0.254 1.034796)
				(xy -0.254 0.933196) (xy -0.2794 0.933196) (xy -0.2794 -0.133604) (xy -0.254 -0.133604) (xy -0.254 -0.235204)
				(xy 0.254 -0.235204) (xy 0.254 -0.133604) (xy 0.2794 -0.133604)
			)
			(stroke
				(width 0)
				(type default)
			)
			(fill no)
			(layer "F.CrtYd")
		)
		(pad "1" smd custom
			(at 0 -0.000254)
			(size 0.127 0.127)
			(layers "F.Cu" "F.Mask" "F.Paste")
			(net "PV_VDDR_NODE1_MODE")
			(options
				(clearance outline)
				(anchor circle)
			)
			(primitives
				(gr_poly
					(pts
						(xy -0.127 0.508) (xy -0.127 -0.0508) (xy -0.254 -0.0508) (xy -0.254 -0.508) (xy 0.254 -0.508)
						(xy 0.254 -0.0508) (xy 0.127 -0.0508) (xy 0.127 0.508)
					)
					(width 0)
					(fill yes)
				)
			)
		)
		(pad "2" smd rect
			(at 0 0.799846 90)
			(size 0.4572 0.508)
			(layers "F.Cu" "F.Mask" "F.Paste")
			(net "P5V_STB_NODE1")
		)
		(zone
			(layer "F.Cu")
			(hatch none 0.5)
			(connect_pads
				(clearance 0)
			)
			(min_thickness 0.25)
			(keepout
				(tracks allowed)
				(vias not_allowed)
				(pads allowed)
				(copperpour not_allowed)
				(footprints allowed)
			)
			(placement
				(enabled no)
				(sheetname "")
			)
			(fill
				(thermal_gap 0.5)
				(thermal_bridge_width 0.5)
				(island_removal_mode 0)
			)
			(polygon
				(pts
					(xy 40.363394 -14.121384) (xy 40.972994 -14.121384) (xy 40.972994 -15.492984) (xy 40.363394 -15.492984)
				)
			)
		)
	)
	(footprint ""
		(layer "F.Cu")
		(at 161.019998 -144.46123)
		(property "Reference" "C438"
			(at -2.221484 -1.354328 0)
			(unlocked yes)
			(layer "F.SilkS")
			(effects
				(font
					(size 0.7874 0.5842)
					(thickness 0.1524)
				)
				(justify left)
			)
		)
		(property "Value" ""
			(at 0 0 0)
			(layer "F.Fab")
			(effects
				(font
					(size 1.27 1.27)
				)
			)
		)
		(duplicate_pad_numbers_are_jumpers no)
		(fp_line
			(start -0.7874 -0.4064)
			(end 0.7874 -0.4064)
			(stroke
				(width 0.1524)
				(type default)
			)
			(layer "F.SilkS")
		)
		(fp_line
			(start -0.7874 0.4064)
			(end -0.7874 -0.4064)
			(stroke
				(width 0.1524)
				(type default)
			)
			(layer "F.SilkS")
		)
		(fp_line
			(start 0 0.381)
			(end 0 -0.381)
			(stroke
				(width 0.1524)
				(type default)
			)
			(layer "F.SilkS")
		)
		(fp_line
			(start 0.7874 -0.4064)
			(end 0.7874 0.4064)
			(stroke
				(width 0.1524)
				(type default)
			)
			(layer "F.SilkS")
		)
		(fp_line
			(start 0.7874 0.4064)
			(end -0.7874 0.4064)
			(stroke
				(width 0.1524)
				(type default)
			)
			(layer "F.SilkS")
		)
		(fp_poly
			(pts
				(xy -0.5334 0.254) (xy -0.635 0.254) (xy -0.635 0.2286) (xy -0.635 -0.254) (xy -0.5334 -0.254) (xy -0.5334 -0.2794)
				(xy 0.5334 -0.2794) (xy 0.5334 -0.254) (xy 0.635 -0.254) (xy 0.635 0.254) (xy 0.5334 0.254) (xy 0.5334 0.2794)
				(xy -0.508 0.2794) (xy -0.5334 0.2794)
			)
			(stroke
				(width 0)
				(type default)
			)
			(fill no)
			(layer "F.CrtYd")
		)
		(pad "1" smd rect
			(at 0.40005 0)
			(size 0.4572 0.508)
			(layers "F.Cu" "F.Mask" "F.Paste")
			(net "LAN2_XTAL_OUT")
		)
		(pad "2" smd rect
			(at -0.40005 0)
			(size 0.4572 0.508)
			(layers "F.Cu" "F.Mask" "F.Paste")
			(net "GND")
		)
	)
	(footprint ""
		(layer "F.Cu")
		(at 178.459892 -139.65301)
		(property "Reference" "C799"
			(at 1.821434 -0.133096 0)
			(unlocked yes)
			(layer "F.SilkS")
			(effects
				(font
					(size 0.7874 0.5842)
					(thickness 0.1524)
				)
				(justify left)
			)
		)
		(property "Value" ""
			(at 0 0 0)
			(layer "F.Fab")
			(effects
				(font
					(size 1.27 1.27)
				)
			)
		)
		(duplicate_pad_numbers_are_jumpers no)
		(fp_line
			(start -0.7874 -0.4064)
			(end 0.7874 -0.4064)
			(stroke
				(width 0.1524)
				(type default)
			)
			(layer "F.SilkS")
		)
		(fp_line
			(start -0.7874 0.4064)
			(end -0.7874 -0.4064)
			(stroke
				(width 0.1524)
				(type default)
			)
			(layer "F.SilkS")
		)
		(fp_line
			(start 0 0.381)
			(end 0 -0.381)
			(stroke
				(width 0.1524)
				(type default)
			)
			(layer "F.SilkS")
		)
		(fp_line
			(start 0.7874 -0.4064)
			(end 0.7874 0.4064)
			(stroke
				(width 0.1524)
				(type default)
			)
			(layer "F.SilkS")
		)
		(fp_line
			(start 0.7874 0.4064)
			(end -0.7874 0.4064)
			(stroke
				(width 0.1524)
				(type default)
			)
			(layer "F.SilkS")
		)
		(fp_poly
			(pts
				(xy -0.5334 0.254) (xy -0.635 0.254) (xy -0.635 0.2286) (xy -0.635 -0.254) (xy -0.5334 -0.254) (xy -0.5334 -0.2794)
				(xy 0.5334 -0.2794) (xy 0.5334 -0.254) (xy 0.635 -0.254) (xy 0.635 0.254) (xy 0.5334 0.254) (xy 0.5334 0.2794)
				(xy -0.508 0.2794) (xy -0.5334 0.2794)
			)
			(stroke
				(width 0)
				(type default)
			)
			(fill no)
			(layer "F.CrtYd")
		)
		(pad "1" smd rect
			(at 0.40005 0)
			(size 0.4572 0.508)
			(layers "F.Cu" "F.Mask" "F.Paste")
			(net "P3V3_STB_NODE1")
		)
		(pad "2" smd rect
			(at -0.40005 0)
			(size 0.4572 0.508)
			(layers "F.Cu" "F.Mask" "F.Paste")
			(net "GND")
		)
	)
	(footprint ""
		(layer "F.Cu")
		(at 57.207912 -100.35921 -90)
		(property "Reference" "R197"
			(at -1.014222 -0.04064 90)
			(unlocked yes)
			(layer "F.SilkS")
			(effects
				(font
					(size 0.7874 0.5842)
					(thickness 0.1524)
				)
				(justify left)
			)
		)
		(property "Value" ""
			(at 0 0 270)
			(layer "F.Fab")
			(effects
				(font
					(size 1.27 1.27)
				)
			)
		)
		(duplicate_pad_numbers_are_jumpers no)
		(fp_line
			(start -0.7874 0.4064)
			(end -0.7874 -0.4064)
			(stroke
				(width 0.1524)
				(type default)
			)
			(layer "F.SilkS")
		)
		(fp_line
			(start 0.7874 0.4064)
			(end -0.7874 0.4064)
			(stroke
				(width 0.1524)
				(type default)
			)
			(layer "F.SilkS")
		)
		(fp_line
			(start -0.7874 -0.4064)
			(end 0.7874 -0.4064)
			(stroke
				(width 0.1524)
				(type default)
			)
			(layer "F.SilkS")
		)
		(fp_line
			(start 0.7874 -0.4064)
			(end 0.7874 0.4064)
			(stroke
				(width 0.1524)
				(type default)
			)
			(layer "F.SilkS")
		)
		(fp_poly
			(pts
				(xy -0.508 0.2794) (xy -0.508 0.2286) (xy -0.635 0.2286) (xy -0.635 -0.254) (xy -0.5334 -0.254)
				(xy -0.5334 -0.2794) (xy 0.5334 -0.2794) (xy 0.5334 -0.254) (xy 0.635 -0.254) (xy 0.635 0.254) (xy 0.5334 0.254)
				(xy 0.5334 0.2794)
			)
			(stroke
				(width 0)
				(type default)
			)
			(fill no)
			(layer "F.CrtYd")
		)
		(pad "1" smd rect
			(at 0.40005 0 270)
			(size 0.4572 0.508)
			(layers "F.Cu" "F.Mask" "F.Paste")
			(net "P3V3_NODE1")
		)
		(pad "2" smd rect
			(at -0.40005 0 270)
			(size 0.4572 0.508)
			(layers "F.Cu" "F.Mask" "F.Paste")
			(net "PU_TEMP1_NODE1_SYS_SHDN_L")
		)
	)
	(footprint ""
		(layer "F.Cu")
		(at 82.414364 -17.679416 90)
		(property "Reference" "C150"
			(at -4.546854 5.52323 90)
			(unlocked yes)
			(layer "F.SilkS")
			(effects
				(font
					(size 0.7874 0.5842)
					(thickness 0.1524)
				)
				(justify left)
			)
		)
		(property "Value" ""
			(at 0 0 90)
			(layer "F.Fab")
			(effects
				(font
					(size 1.27 1.27)
				)
			)
		)
		(duplicate_pad_numbers_are_jumpers no)
		(fp_line
			(start 0.7874 -0.4064)
			(end 0.7874 0.4064)
			(stroke
				(width 0.1524)
				(type default)
			)
			(layer "F.SilkS")
		)
		(fp_line
			(start -0.7874 -0.4064)
			(end 0.7874 -0.4064)
			(stroke
				(width 0.1524)
				(type default)
			)
			(layer "F.SilkS")
		)
		(fp_line
			(start 0 0.381)
			(end 0 -0.381)
			(stroke
				(width 0.1524)
				(type default)
			)
			(layer "F.SilkS")
		)
		(fp_line
			(start 0.7874 0.4064)
			(end -0.7874 0.4064)
			(stroke
				(width 0.1524)
				(type default)
			)
			(layer "F.SilkS")
		)
		(fp_line
			(start -0.7874 0.4064)
			(end -0.7874 -0.4064)
			(stroke
				(width 0.1524)
				(type default)
			)
			(layer "F.SilkS")
		)
		(fp_poly
			(pts
				(xy -0.5334 0.254) (xy -0.635 0.254) (xy -0.635 0.2286) (xy -0.635 -0.254) (xy -0.5334 -0.254) (xy -0.5334 -0.2794)
				(xy 0.5334 -0.2794) (xy 0.5334 -0.254) (xy 0.635 -0.254) (xy 0.635 0.254) (xy 0.5334 0.254) (xy 0.5334 0.2794)
				(xy -0.508 0.2794) (xy -0.5334 0.2794)
			)
			(stroke
				(width 0)
				(type default)
			)
			(fill no)
			(layer "F.CrtYd")
		)
		(pad "1" smd rect
			(at 0.40005 0 90)
			(size 0.4572 0.508)
			(layers "F.Cu" "F.Mask" "F.Paste")
			(net "PV_VDDR_NODE1")
		)
		(pad "2" smd rect
			(at -0.40005 0 90)
			(size 0.4572 0.508)
			(layers "F.Cu" "F.Mask" "F.Paste")
			(net "GND")
		)
	)
	(footprint ""
		(layer "F.Cu")
		(at 145.65376 -188.126624 -90)
		(property "Reference" "R993"
			(at -5.519674 1.030732 90)
			(unlocked yes)
			(layer "F.SilkS")
			(effects
				(font
					(size 0.7874 0.5842)
					(thickness 0.1524)
				)
				(justify left)
			)
		)
		(property "Value" ""
			(at 0 0 270)
			(layer "F.Fab")
			(effects
				(font
					(size 1.27 1.27)
				)
			)
		)
		(duplicate_pad_numbers_are_jumpers no)
		(fp_line
			(start -0.7874 0.4064)
			(end -0.7874 -0.4064)
			(stroke
				(width 0.1524)
				(type default)
			)
			(layer "F.SilkS")
		)
		(fp_line
			(start 0.7874 0.4064)
			(end -0.7874 0.4064)
			(stroke
				(width 0.1524)
				(type default)
			)
			(layer "F.SilkS")
		)
		(fp_line
			(start -0.7874 -0.4064)
			(end 0.7874 -0.4064)
			(stroke
				(width 0.1524)
				(type default)
			)
			(layer "F.SilkS")
		)
		(fp_line
			(start 0.7874 -0.4064)
			(end 0.7874 0.4064)
			(stroke
				(width 0.1524)
				(type default)
			)
			(layer "F.SilkS")
		)
		(fp_poly
			(pts
				(xy -0.508 0.2794) (xy -0.508 0.2286) (xy -0.635 0.2286) (xy -0.635 -0.254) (xy -0.5334 -0.254)
				(xy -0.5334 -0.2794) (xy 0.5334 -0.2794) (xy 0.5334 -0.254) (xy 0.635 -0.254) (xy 0.635 0.254) (xy 0.5334 0.254)
				(xy 0.5334 0.2794)
			)
			(stroke
				(width 0)
				(type default)
			)
			(fill no)
			(layer "F.CrtYd")
		)
		(pad "1" smd rect
			(at 0.40005 0 270)
			(size 0.4572 0.508)
			(layers "F.Cu" "F.Mask" "F.Paste")
			(net "UART_T12_NODE3_RXD")
		)
		(pad "2" smd rect
			(at -0.40005 0 270)
			(size 0.4572 0.508)
			(layers "F.Cu" "F.Mask" "F.Paste")
			(net "UART_T12_NODE3_RXD_R")
		)
	)
	(footprint ""
		(layer "F.Cu")
		(at 119.12473 -41.529762 180)
		(property "Reference" "R625"
			(at 1.020318 -4.024884 0)
			(unlocked yes)
			(layer "F.SilkS")
			(effects
				(font
					(size 0.7874 0.5842)
					(thickness 0.1524)
				)
				(justify left)
			)
		)
		(property "Value" ""
			(at 0 0 180)
			(layer "F.Fab")
			(effects
				(font
					(size 1.27 1.27)
				)
			)
		)
		(duplicate_pad_numbers_are_jumpers no)
		(fp_line
			(start 0.7874 0.4064)
			(end -0.7874 0.4064)
			(stroke
				(width 0.1524)
				(type default)
			)
			(layer "F.SilkS")
		)
		(fp_line
			(start 0.7874 -0.4064)
			(end 0.7874 0.4064)
			(stroke
				(width 0.1524)
				(type default)
			)
			(layer "F.SilkS")
		)
		(fp_line
			(start -0.7874 0.4064)
			(end -0.7874 -0.4064)
			(stroke
				(width 0.1524)
				(type default)
			)
			(layer "F.SilkS")
		)
		(fp_line
			(start -0.7874 -0.4064)
			(end 0.7874 -0.4064)
			(stroke
				(width 0.1524)
				(type default)
			)
			(layer "F.SilkS")
		)
		(fp_poly
			(pts
				(xy -0.508 0.2794) (xy -0.508 0.2286) (xy -0.635 0.2286) (xy -0.635 -0.254) (xy -0.5334 -0.254)
				(xy -0.5334 -0.2794) (xy 0.5334 -0.2794) (xy 0.5334 -0.254) (xy 0.635 -0.254) (xy 0.635 0.254) (xy 0.5334 0.254)
				(xy 0.5334 0.2794)
			)
			(stroke
				(width 0)
				(type default)
			)
			(fill no)
			(layer "F.CrtYd")
		)
		(pad "1" smd rect
			(at 0.40005 0 180)
			(size 0.4572 0.508)
			(layers "F.Cu" "F.Mask" "F.Paste")
			(net "LPC_CPU_NODE1_CLKOUT1")
		)
		(pad "2" smd rect
			(at -0.40005 0 180)
			(size 0.4572 0.508)
			(layers "F.Cu" "F.Mask" "F.Paste")
			(net "SIO_PCICLK33")
		)
	)
	(footprint ""
		(layer "F.Cu")
		(at 33.344104 -116.518182 180)
		(property "Reference" "R1240"
			(at 6.054344 -1.034034 0)
			(unlocked yes)
			(layer "F.SilkS")
			(effects
				(font
					(size 0.7874 0.5842)
					(thickness 0.1524)
				)
				(justify left)
			)
		)
		(property "Value" ""
			(at 0 0 180)
			(layer "F.Fab")
			(effects
				(font
					(size 1.27 1.27)
				)
			)
		)
		(duplicate_pad_numbers_are_jumpers no)
		(fp_line
			(start 0.7874 0.4064)
			(end -0.7874 0.4064)
			(stroke
				(width 0.1524)
				(type default)
			)
			(layer "F.SilkS")
		)
		(fp_line
			(start 0.7874 -0.4064)
			(end 0.7874 0.4064)
			(stroke
				(width 0.1524)
				(type default)
			)
			(layer "F.SilkS")
		)
		(fp_line
			(start -0.7874 0.4064)
			(end -0.7874 -0.4064)
			(stroke
				(width 0.1524)
				(type default)
			)
			(layer "F.SilkS")
		)
		(fp_line
			(start -0.7874 -0.4064)
			(end 0.7874 -0.4064)
			(stroke
				(width 0.1524)
				(type default)
			)
			(layer "F.SilkS")
		)
		(fp_poly
			(pts
				(xy -0.508 0.2794) (xy -0.508 0.2286) (xy -0.635 0.2286) (xy -0.635 -0.254) (xy -0.5334 -0.254)
				(xy -0.5334 -0.2794) (xy 0.5334 -0.2794) (xy 0.5334 -0.254) (xy 0.635 -0.254) (xy 0.635 0.254) (xy 0.5334 0.254)
				(xy 0.5334 0.2794)
			)
			(stroke
				(width 0)
				(type default)
			)
			(fill no)
			(layer "F.CrtYd")
		)
		(pad "1" smd rect
			(at 0.40005 0 180)
			(size 0.4572 0.508)
			(layers "F.Cu" "F.Mask" "F.Paste")
			(net "GND")
		)
		(pad "2" smd rect
			(at -0.40005 0 180)
			(size 0.4572 0.508)
			(layers "F.Cu" "F.Mask" "F.Paste")
			(net "FM_CPLD_NODE1_P1V5_EN")
		)
	)
	(footprint ""
		(layer "F.Cu")
		(at 32.309308 -187.46851)
		(property "Reference" "R1025"
			(at -3.42011 -4.706874 0)
			(unlocked yes)
			(layer "F.SilkS")
			(effects
				(font
					(size 0.7874 0.5842)
					(thickness 0.1524)
				)
			)
		)
		(property "Value" ""
			(at 0 0 0)
			(layer "F.Fab")
			(effects
				(font
					(size 1.27 1.27)
				)
			)
		)
		(duplicate_pad_numbers_are_jumpers no)
		(fp_line
			(start -1.2954 -0.5842)
			(end 1.2954 -0.5842)
			(stroke
				(width 0.1524)
				(type default)
			)
			(layer "F.SilkS")
		)
		(fp_line
			(start -1.2954 0.5842)
			(end -1.2954 -0.5842)
			(stroke
				(width 0.1524)
				(type default)
			)
			(layer "F.SilkS")
		)
		(fp_line
			(start 1.2954 -0.5842)
			(end 1.2954 0.5842)
			(stroke
				(width 0.1524)
				(type default)
			)
			(layer "F.SilkS")
		)
		(fp_line
			(start 1.2954 0.5842)
			(end -1.2954 0.5842)
			(stroke
				(width 0.1524)
				(type default)
			)
			(layer "F.SilkS")
		)
		(fp_poly
			(pts
				(xy 1.143 -0.3556) (xy 1.143 0.3556) (xy 0.8636 0.3556) (xy 0.8636 0.4572) (xy -0.8636 0.4572) (xy -0.8636 0.4318)
				(xy -0.8636 0.3556) (xy -1.143 0.3556) (xy -1.143 -0.3556) (xy -0.8636 -0.3556) (xy -0.8636 -0.4572)
				(xy 0.8636 -0.4572) (xy 0.8636 -0.3556)
			)
			(stroke
				(width 0)
				(type default)
			)
			(fill no)
			(layer "F.CrtYd")
		)
		(pad "1" smd rect
			(at 0.7366 0 90)
			(size 0.7112 0.8128)
			(layers "F.Cu" "F.Mask" "F.Paste")
			(net "AGND_HSC_NODE1")
		)
		(pad "2" smd rect
			(at -0.7366 0 90)
			(size 0.7112 0.8128)
			(layers "F.Cu" "F.Mask" "F.Paste")
			(net "GND")
		)
	)
	(footprint ""
		(layer "F.Cu")
		(at 75.67676 -188.126624 -90)
		(property "Reference" "R938"
			(at -4.548886 1.292098 90)
			(unlocked yes)
			(layer "F.SilkS")
			(effects
				(font
					(size 0.7874 0.5842)
					(thickness 0.1524)
				)
				(justify left)
			)
		)
		(property "Value" ""
			(at 0 0 270)
			(layer "F.Fab")
			(effects
				(font
					(size 1.27 1.27)
				)
			)
		)
		(duplicate_pad_numbers_are_jumpers no)
		(fp_line
			(start -0.7874 0.4064)
			(end -0.7874 -0.4064)
			(stroke
				(width 0.1524)
				(type default)
			)
			(layer "F.SilkS")
		)
		(fp_line
			(start 0.7874 0.4064)
			(end -0.7874 0.4064)
			(stroke
				(width 0.1524)
				(type default)
			)
			(layer "F.SilkS")
		)
		(fp_line
			(start -0.7874 -0.4064)
			(end 0.7874 -0.4064)
			(stroke
				(width 0.1524)
				(type default)
			)
			(layer "F.SilkS")
		)
		(fp_line
			(start 0.7874 -0.4064)
			(end 0.7874 0.4064)
			(stroke
				(width 0.1524)
				(type default)
			)
			(layer "F.SilkS")
		)
		(fp_poly
			(pts
				(xy -0.508 0.2794) (xy -0.508 0.2286) (xy -0.635 0.2286) (xy -0.635 -0.254) (xy -0.5334 -0.254)
				(xy -0.5334 -0.2794) (xy 0.5334 -0.2794) (xy 0.5334 -0.254) (xy 0.635 -0.254) (xy 0.635 0.254) (xy 0.5334 0.254)
				(xy 0.5334 0.2794)
			)
			(stroke
				(width 0)
				(type default)
			)
			(fill no)
			(layer "F.CrtYd")
		)
		(pad "1" smd rect
			(at 0.40005 0 270)
			(size 0.4572 0.508)
			(layers "F.Cu" "F.Mask" "F.Paste")
			(net "UART_T4_NODE2_RXD")
		)
		(pad "2" smd rect
			(at -0.40005 0 270)
			(size 0.4572 0.508)
			(layers "F.Cu" "F.Mask" "F.Paste")
			(net "UART_T4_NODE2_RXD_R")
		)
	)
)
